(kicad_pcb
	(version 20260206)
	(generator "pcbnew")
	(generator_version "10.0")
	(general
		(thickness 1.6)
		(legacy_teardrops no)
	)
	(paper "A4")
	(title_block
		(title "03242023_DA0F0TMBIJ0_F0T_Motherboard_J_brd_V01_OCP.brd")
		(comment 1 "Grand Teton / footprints 2493-2497 of 6105")
	)
	(layers
		(0 "F.Cu" signal "TOP")
		(4 "In1.Cu" signal "GND")
		(6 "In2.Cu" signal "IN1")
		(8 "In3.Cu" signal "GND1")
		(10 "In4.Cu" signal "IN2")
		(12 "In5.Cu" signal "GND2")
		(14 "In6.Cu" signal "IN3")
		(16 "In7.Cu" signal "GND3")
		(18 "In8.Cu" signal "VCC")
		(20 "In9.Cu" signal "VCC1")
		(22 "In10.Cu" signal "GND4")
		(24 "In11.Cu" signal "IN4")
		(26 "In12.Cu" signal "GND5")
		(28 "In13.Cu" signal "IN5")
		(30 "In14.Cu" signal "GND6")
		(32 "In15.Cu" signal "IN6")
		(34 "In16.Cu" signal "GND7")
		(2 "B.Cu" signal "BOTTOM")
		(9 "F.Adhes" user "F.Adhesive")
		(11 "B.Adhes" user "B.Adhesive")
		(13 "F.Paste" user "Package Geometry/Pastemask Top")
		(15 "B.Paste" user "Package Geometry/Pastemask Bottom")
		(5 "F.SilkS" user "Ref Des/Silkscreen Top")
		(7 "B.SilkS" user "Ref Des/Silkscreen Bottom")
		(1 "F.Mask" user "Board Geometry/Soldermask Top")
		(3 "B.Mask" user "Board Geometry/Soldermask Bottom")
		(17 "Dwgs.User" user "User.Drawings")
		(19 "Cmts.User" user "User.Comments")
		(21 "Eco1.User" user "User.Eco1")
		(23 "Eco2.User" user "User.Eco2")
		(25 "Edge.Cuts" user "Board Geometry/Outline")
		(27 "Margin" user)
		(31 "F.CrtYd" user "Package Geometry/Place Bound Top")
		(29 "B.CrtYd" user "Package Geometry/Place Bound Bottom")
		(35 "F.Fab" user "Ref Des/Assembly Top")
		(33 "B.Fab" user "Ref Des/Assembly Bottom")
	)
	(footprint ""
		(layer "F.Cu")
		(at 379.36551 -341.729822 -90)
		(property "Reference" "PC257"
			(at 0 0 270)
			(layer "F.SilkS")
			(hide yes)
			(effects
				(font
					(size 1.27 1.27)
				)
			)
		)
		(property "Value" ""
			(at 0 0 270)
			(layer "F.Fab")
			(effects
				(font
					(size 1.27 1.27)
				)
			)
		)
		(duplicate_pad_numbers_are_jumpers no)
		(fp_line
			(start -0.7874 0.4064)
			(end -0.7874 -0.4064)
			(stroke
				(width 0.1524)
				(type default)
			)
			(layer "F.SilkS")
		)
		(fp_line
			(start 0.7874 0.4064)
			(end -0.7874 0.4064)
			(stroke
				(width 0.1524)
				(type default)
			)
			(layer "F.SilkS")
		)
		(fp_line
			(start -0.7874 -0.4064)
			(end 0.7874 -0.4064)
			(stroke
				(width 0.1524)
				(type default)
			)
			(layer "F.SilkS")
		)
		(fp_line
			(start 0.7874 -0.4064)
			(end 0.7874 0.4064)
			(stroke
				(width 0.1524)
				(type default)
			)
			(layer "F.SilkS")
		)
		(fp_line
			(start -0.67945 0.3048)
			(end -0.67945 -0.305054)
			(stroke
				(width 0.1)
				(type default)
			)
			(layer "F.Fab")
		)
		(fp_line
			(start -0.12065 0.3048)
			(end -0.67945 0.3048)
			(stroke
				(width 0.1)
				(type default)
			)
			(layer "F.Fab")
		)
		(fp_line
			(start 0.120396 0.3048)
			(end 0.120396 0.2794)
			(stroke
				(width 0.1)
				(type default)
			)
			(layer "F.Fab")
		)
		(fp_line
			(start 0.67945 0.3048)
			(end 0.120396 0.3048)
			(stroke
				(width 0.1)
				(type default)
			)
			(layer "F.Fab")
		)
		(fp_line
			(start -0.12065 0.2794)
			(end -0.12065 0.3048)
			(stroke
				(width 0.1)
				(type default)
			)
			(layer "F.Fab")
		)
		(fp_line
			(start 0.120396 0.2794)
			(end -0.12065 0.2794)
			(stroke
				(width 0.1)
				(type default)
			)
			(layer "F.Fab")
		)
		(fp_line
			(start -0.12065 -0.2794)
			(end 0.12065 -0.2794)
			(stroke
				(width 0.1)
				(type default)
			)
			(layer "F.Fab")
		)
		(fp_line
			(start 0.12065 -0.2794)
			(end 0.12065 -0.3048)
			(stroke
				(width 0.1)
				(type default)
			)
			(layer "F.Fab")
		)
		(fp_line
			(start 0.12065 -0.3048)
			(end 0.67945 -0.3048)
			(stroke
				(width 0.1)
				(type default)
			)
			(layer "F.Fab")
		)
		(fp_line
			(start 0.67945 -0.3048)
			(end 0.67945 0.3048)
			(stroke
				(width 0.1)
				(type default)
			)
			(layer "F.Fab")
		)
		(fp_line
			(start -0.67945 -0.305054)
			(end -0.12065 -0.305054)
			(stroke
				(width 0.1)
				(type default)
			)
			(layer "F.Fab")
		)
		(fp_line
			(start -0.12065 -0.305054)
			(end -0.12065 -0.2794)
			(stroke
				(width 0.1)
				(type default)
			)
			(layer "F.Fab")
		)
		(pad "1" smd circle
			(at -0.40005 0 270)
			(size 0 0)
			(layers "F.Cu" "F.Mask" "F.Paste")
			(net "SW_PVCCIN_CPU0_BOOT5_R")
		)
		(pad "2" smd circle
			(at 0.40005 0 270)
			(size 0 0)
			(layers "F.Cu" "F.Mask" "F.Paste")
			(net "SW_PVCCIN_CPU0_BOOTR5")
		)
	)
	(footprint ""
		(layer "F.Cu")
		(at 408.15641 -402.371052 -90)
		(property "Reference" "C959"
			(at 0 0 270)
			(layer "F.SilkS")
			(hide yes)
			(effects
				(font
					(size 1.27 1.27)
				)
			)
		)
		(property "Value" ""
			(at 0 0 270)
			(layer "F.Fab")
			(effects
				(font
					(size 1.27 1.27)
				)
			)
		)
		(duplicate_pad_numbers_are_jumpers no)
		(fp_line
			(start -0.299974 0.150114)
			(end -0.299974 -0.150114)
			(stroke
				(width 0.1)
				(type default)
			)
			(layer "F.Fab")
		)
		(fp_line
			(start 0.299974 0.150114)
			(end -0.299974 0.150114)
			(stroke
				(width 0.1)
				(type default)
			)
			(layer "F.Fab")
		)
		(fp_line
			(start -0.299974 -0.150114)
			(end 0.299974 -0.150114)
			(stroke
				(width 0.1)
				(type default)
			)
			(layer "F.Fab")
		)
		(fp_line
			(start 0.299974 -0.150114)
			(end 0.299974 0.150114)
			(stroke
				(width 0.1)
				(type default)
			)
			(layer "F.Fab")
		)
		(pad "1" smd rect
			(at -0.2667 0 270)
			(size 0.3048 0.381)
			(layers "F.Cu" "F.Mask" "F.Paste")
			(net "P5E_CPU0_PE2_TX_C_DP<3>")
		)
		(pad "2" smd rect
			(at 0.2667 0 270)
			(size 0.3048 0.381)
			(layers "F.Cu" "F.Mask" "F.Paste")
			(net "P5E_CPU0_PE2_TX_DP<3>")
		)
	)
	(footprint ""
		(layer "F.Cu")
		(at 190.291466 -126.963678 -90)
		(property "Reference" "R4600"
			(at 0 0 270)
			(layer "F.SilkS")
			(hide yes)
			(effects
				(font
					(size 1.27 1.27)
				)
			)
		)
		(property "Value" ""
			(at 0 0 270)
			(layer "F.Fab")
			(effects
				(font
					(size 1.27 1.27)
				)
			)
		)
		(duplicate_pad_numbers_are_jumpers no)
		(fp_line
			(start -0.7874 0.4064)
			(end -0.7874 -0.4064)
			(stroke
				(width 0.1524)
				(type default)
			)
			(layer "F.SilkS")
		)
		(fp_line
			(start 0.7874 0.4064)
			(end -0.7874 0.4064)
			(stroke
				(width 0.1524)
				(type default)
			)
			(layer "F.SilkS")
		)
		(fp_line
			(start -0.7874 -0.4064)
			(end 0.7874 -0.4064)
			(stroke
				(width 0.1524)
				(type default)
			)
			(layer "F.SilkS")
		)
		(fp_line
			(start 0.7874 -0.4064)
			(end 0.7874 0.4064)
			(stroke
				(width 0.1524)
				(type default)
			)
			(layer "F.SilkS")
		)
		(fp_line
			(start -0.67945 0.3048)
			(end -0.67945 -0.305054)
			(stroke
				(width 0.1)
				(type default)
			)
			(layer "F.Fab")
		)
		(fp_line
			(start -0.12065 0.3048)
			(end -0.67945 0.3048)
			(stroke
				(width 0.1)
				(type default)
			)
			(layer "F.Fab")
		)
		(fp_line
			(start 0.120396 0.3048)
			(end 0.120396 0.2794)
			(stroke
				(width 0.1)
				(type default)
			)
			(layer "F.Fab")
		)
		(fp_line
			(start 0.67945 0.3048)
			(end 0.120396 0.3048)
			(stroke
				(width 0.1)
				(type default)
			)
			(layer "F.Fab")
		)
		(fp_line
			(start -0.12065 0.2794)
			(end -0.12065 0.3048)
			(stroke
				(width 0.1)
				(type default)
			)
			(layer "F.Fab")
		)
		(fp_line
			(start 0.120396 0.2794)
			(end -0.12065 0.2794)
			(stroke
				(width 0.1)
				(type default)
			)
			(layer "F.Fab")
		)
		(fp_line
			(start -0.12065 -0.2794)
			(end 0.12065 -0.2794)
			(stroke
				(width 0.1)
				(type default)
			)
			(layer "F.Fab")
		)
		(fp_line
			(start 0.12065 -0.2794)
			(end 0.12065 -0.3048)
			(stroke
				(width 0.1)
				(type default)
			)
			(layer "F.Fab")
		)
		(fp_line
			(start 0.12065 -0.3048)
			(end 0.67945 -0.3048)
			(stroke
				(width 0.1)
				(type default)
			)
			(layer "F.Fab")
		)
		(fp_line
			(start 0.67945 -0.3048)
			(end 0.67945 0.3048)
			(stroke
				(width 0.1)
				(type default)
			)
			(layer "F.Fab")
		)
		(fp_line
			(start -0.67945 -0.305054)
			(end -0.12065 -0.305054)
			(stroke
				(width 0.1)
				(type default)
			)
			(layer "F.Fab")
		)
		(fp_line
			(start -0.12065 -0.305054)
			(end -0.12065 -0.2794)
			(stroke
				(width 0.1)
				(type default)
			)
			(layer "F.Fab")
		)
		(pad "1" smd circle
			(at -0.40005 0 270)
			(size 0 0)
			(layers "F.Cu" "F.Mask" "F.Paste")
			(net "HP_LVC3_OCP_V3_1_P12V_PWRGD")
		)
		(pad "2" smd circle
			(at 0.40005 0 270)
			(size 0 0)
			(layers "F.Cu" "F.Mask" "F.Paste")
			(net "HP_LVC3_OCP_V3_1_HSC_PWRGD_PLD_")
		)
	)
	(footprint ""
		(layer "F.Cu")
		(at 116.71808 -393.937998 90)
		(property "Reference" "R3029"
			(at 0 0 90)
			(layer "F.SilkS")
			(hide yes)
			(effects
				(font
					(size 1.27 1.27)
				)
			)
		)
		(property "Value" ""
			(at 0 0 90)
			(layer "F.Fab")
			(effects
				(font
					(size 1.27 1.27)
				)
			)
		)
		(duplicate_pad_numbers_are_jumpers no)
		(fp_line
			(start 0.7874 -0.4064)
			(end 0.7874 0.4064)
			(stroke
				(width 0.1524)
				(type default)
			)
			(layer "F.SilkS")
		)
		(fp_line
			(start -0.7874 -0.4064)
			(end 0.7874 -0.4064)
			(stroke
				(width 0.1524)
				(type default)
			)
			(layer "F.SilkS")
		)
		(fp_line
			(start 0.7874 0.4064)
			(end -0.7874 0.4064)
			(stroke
				(width 0.1524)
				(type default)
			)
			(layer "F.SilkS")
		)
		(fp_line
			(start -0.7874 0.4064)
			(end -0.7874 -0.4064)
			(stroke
				(width 0.1524)
				(type default)
			)
			(layer "F.SilkS")
		)
		(fp_line
			(start -0.12065 -0.305054)
			(end -0.12065 -0.2794)
			(stroke
				(width 0.1)
				(type default)
			)
			(layer "F.Fab")
		)
		(fp_line
			(start -0.67945 -0.305054)
			(end -0.12065 -0.305054)
			(stroke
				(width 0.1)
				(type default)
			)
			(layer "F.Fab")
		)
		(fp_line
			(start 0.67945 -0.3048)
			(end 0.67945 0.3048)
			(stroke
				(width 0.1)
				(type default)
			)
			(layer "F.Fab")
		)
		(fp_line
			(start 0.12065 -0.3048)
			(end 0.67945 -0.3048)
			(stroke
				(width 0.1)
				(type default)
			)
			(layer "F.Fab")
		)
		(fp_line
			(start 0.12065 -0.2794)
			(end 0.12065 -0.3048)
			(stroke
				(width 0.1)
				(type default)
			)
			(layer "F.Fab")
		)
		(fp_line
			(start -0.12065 -0.2794)
			(end 0.12065 -0.2794)
			(stroke
				(width 0.1)
				(type default)
			)
			(layer "F.Fab")
		)
		(fp_line
			(start 0.120396 0.2794)
			(end -0.12065 0.2794)
			(stroke
				(width 0.1)
				(type default)
			)
			(layer "F.Fab")
		)
		(fp_line
			(start -0.12065 0.2794)
			(end -0.12065 0.3048)
			(stroke
				(width 0.1)
				(type default)
			)
			(layer "F.Fab")
		)
		(fp_line
			(start 0.67945 0.3048)
			(end 0.120396 0.3048)
			(stroke
				(width 0.1)
				(type default)
			)
			(layer "F.Fab")
		)
		(fp_line
			(start 0.120396 0.3048)
			(end 0.120396 0.2794)
			(stroke
				(width 0.1)
				(type default)
			)
			(layer "F.Fab")
		)
		(fp_line
			(start -0.12065 0.3048)
			(end -0.67945 0.3048)
			(stroke
				(width 0.1)
				(type default)
			)
			(layer "F.Fab")
		)
		(fp_line
			(start -0.67945 0.3048)
			(end -0.67945 -0.305054)
			(stroke
				(width 0.1)
				(type default)
			)
			(layer "F.Fab")
		)
		(pad "1" smd circle
			(at -0.40005 0 90)
			(size 0 0)
			(layers "F.Cu" "F.Mask" "F.Paste")
			(net "P3V3_AUX")
		)
		(pad "2" smd circle
			(at 0.40005 0 90)
			(size 0 0)
			(layers "F.Cu" "F.Mask" "F.Paste")
			(net "FM_SMB_1_ALERT_GPU")
		)
	)
	(footprint ""
		(layer "F.Cu")
		(at 210.840066 -402.722842 180)
		(property "Reference" "PU288"
			(at 0.323596 8.166608 0)
			(unlocked yes)
			(layer "F.SilkS")
			(effects
				(font
					(size 0.7874 0.5842)
					(thickness 0.1524)
				)
			)
		)
		(property "Value" ""
			(at 0 0 180)
			(layer "F.Fab")
			(effects
				(font
					(size 1.27 1.27)
				)
			)
		)
		(duplicate_pad_numbers_are_jumpers no)
		(fp_line
			(start 2.567686 2.567686)
			(end 2.567686 -2.567686)
			(stroke
				(width 0.1524)
				(type default)
			)
			(layer "F.SilkS")
		)
		(fp_line
			(start 2.567686 -2.567686)
			(end -2.567686 -2.567686)
			(stroke
				(width 0.1524)
				(type default)
			)
			(layer "F.SilkS")
		)
		(fp_line
			(start -2.567686 2.567686)
			(end 2.567686 2.567686)
			(stroke
				(width 0.1524)
				(type default)
			)
			(layer "F.SilkS")
		)
		(fp_line
			(start -2.567686 -2.567686)
			(end -2.567686 2.567686)
			(stroke
				(width 0.1524)
				(type default)
			)
			(layer "F.SilkS")
		)
		(fp_poly
			(pts
				(xy -3.120898 -3.448558) (xy -2.761742 -2.370836) (xy -3.83921 -2.729992)
			)
			(stroke
				(width 0)
				(type default)
			)
			(fill yes)
			(layer "F.SilkS")
		)
		(fp_line
			(start 2.549906 2.549906)
			(end 2.549906 -2.549906)
			(stroke
				(width 0.1)
				(type default)
			)
			(layer "F.Fab")
		)
		(fp_line
			(start 2.549906 -2.549906)
			(end -2.549906 -2.549906)
			(stroke
				(width 0.1)
				(type default)
			)
			(layer "F.Fab")
		)
		(fp_line
			(start -2.549906 2.549906)
			(end 2.549906 2.549906)
			(stroke
				(width 0.1)
				(type default)
			)
			(layer "F.Fab")
		)
		(fp_line
			(start -2.549906 -2.549906)
			(end -2.549906 2.549906)
			(stroke
				(width 0.1)
				(type default)
			)
			(layer "F.Fab")
		)
		(fp_poly
			(pts
				(xy -3.806698 -2.25806) (xy -3.806698 -1.24206) (xy -2.790698 -1.75006)
			)
			(stroke
				(width 0)
				(type default)
			)
			(fill yes)
			(layer "F.Fab")
		)
		(pad "1" smd rect
			(at -2.250186 -1.75006 270)
			(size 0.254 0.3556)
			(layers "F.Cu" "F.Mask" "F.Paste")
			(net "P12V_AUX")
		)
		(pad "2" smd rect
			(at -2.237486 -1.249934 270)
			(size 0.254 0.381)
			(layers "F.Cu" "F.Mask" "F.Paste")
			(net "P12V_AUX")
		)
		(pad "3" smd rect
			(at -2.237486 -0.750062 270)
			(size 0.254 0.381)
			(layers "F.Cu" "F.Mask" "F.Paste")
			(net "HSC_D_OC_2")
		)
		(pad "4" smd rect
			(at -2.237486 -0.249936 270)
			(size 0.254 0.381)
			(layers "F.Cu" "F.Mask" "F.Paste")
			(net "HSC_ON")
		)
		(pad "5" smd rect
			(at -2.237486 0.249936 270)
			(size 0.254 0.381)
			(layers "F.Cu" "F.Mask" "F.Paste")
			(net "HSC_FAULT")
		)
		(pad "6" smd rect
			(at -2.237486 0.750062 270)
			(size 0.254 0.381)
			(layers "F.Cu" "F.Mask" "F.Paste")
			(net "HSC_FLT_TYPE_2")
		)
		(pad "7" smd rect
			(at -2.237486 1.249934 270)
			(size 0.254 0.381)
			(layers "F.Cu" "F.Mask" "F.Paste")
			(net "HSC_NC1_2")
		)
		(pad "8" smd rect
			(at -2.250186 1.75006 270)
			(size 0.254 0.3556)
			(layers "F.Cu" "F.Mask" "F.Paste")
			(net "HSC_MODE_2")
		)
		(pad "9" smd rect
			(at -1.75006 2.250186 180)
			(size 0.254 0.3556)
			(layers "F.Cu" "F.Mask" "F.Paste")
			(net "P12V_PSU")
		)
		(pad "10" smd rect
			(at -1.249934 2.237486 180)
			(size 0.254 0.381)
			(layers "F.Cu" "F.Mask" "F.Paste")
			(net "P12V_PSU")
		)
		(pad "11" smd rect
			(at -0.750062 2.237486 180)
			(size 0.254 0.381)
			(layers "F.Cu" "F.Mask" "F.Paste")
			(net "P12V_PSU")
		)
		(pad "12" smd rect
			(at -0.249936 2.237486 180)
			(size 0.254 0.381)
			(layers "F.Cu" "F.Mask" "F.Paste")
			(net "P12V_PSU")
		)
		(pad "13" smd rect
			(at 0.249936 2.237486 180)
			(size 0.254 0.381)
			(layers "F.Cu" "F.Mask" "F.Paste")
			(net "P12V_PSU")
		)
		(pad "14" smd rect
			(at 0.750062 2.237486 180)
			(size 0.254 0.381)
			(layers "F.Cu" "F.Mask" "F.Paste")
			(net "P12V_PSU")
		)
		(pad "15" smd rect
			(at 1.249934 2.237486 180)
			(size 0.254 0.381)
			(layers "F.Cu" "F.Mask" "F.Paste")
			(net "P12V_PSU")
		)
		(pad "16" smd rect
			(at 1.75006 2.250186 180)
			(size 0.254 0.3556)
			(layers "F.Cu" "F.Mask" "F.Paste")
			(net "P12V_PSU")
		)
		(pad "17" smd rect
			(at 2.250186 1.75006 270)
			(size 0.254 0.3556)
			(layers "F.Cu" "F.Mask" "F.Paste")
			(net "HSC_SCREF_2")
		)
		(pad "18" smd rect
			(at 2.237486 1.249934 270)
			(size 0.254 0.381)
			(layers "F.Cu" "F.Mask" "F.Paste")
			(net "HSC_VTEMP")
		)
		(pad "19" smd rect
			(at 2.237486 0.750062 270)
			(size 0.254 0.381)
			(layers "F.Cu" "F.Mask" "F.Paste")
			(net "HSC_SS")
		)
		(pad "20" smd rect
			(at 2.237486 0.249936 270)
			(size 0.254 0.381)
			(layers "F.Cu" "F.Mask" "F.Paste")
			(net "AGND_HSC")
		)
		(pad "21" smd rect
			(at 2.237486 -0.249936 270)
			(size 0.254 0.381)
			(layers "F.Cu" "F.Mask" "F.Paste")
			(net "HSC_VDD_R_2")
		)
		(pad "22" smd rect
			(at 2.237486 -0.750062 270)
			(size 0.254 0.381)
			(layers "F.Cu" "F.Mask" "F.Paste")
			(net "HSC_IMON")
		)
		(pad "23" smd rect
			(at 2.237486 -1.249934 270)
			(size 0.254 0.381)
			(layers "F.Cu" "F.Mask" "F.Paste")
			(net "HSC_CS_2")
		)
		(pad "24" smd rect
			(at 2.250186 -1.75006 270)
			(size 0.254 0.3556)
			(layers "F.Cu" "F.Mask" "F.Paste")
			(net "HSC_OCREF")
		)
		(pad "25" smd rect
			(at 1.75006 -2.250186 180)
			(size 0.254 0.3556)
			(layers "F.Cu" "F.Mask" "F.Paste")
			(net "P12V_AUX")
		)
		(pad "26" smd rect
			(at 1.249934 -2.237486 180)
			(size 0.254 0.381)
			(layers "F.Cu" "F.Mask" "F.Paste")
			(net "P12V_AUX")
		)
		(pad "27" smd rect
			(at 0.750062 -2.237486 180)
			(size 0.254 0.381)
			(layers "F.Cu" "F.Mask" "F.Paste")
			(net "P12V_AUX")
		)
		(pad "28" smd rect
			(at 0.249936 -2.237486 180)
			(size 0.254 0.381)
			(layers "F.Cu" "F.Mask" "F.Paste")
			(net "P12V_AUX")
		)
		(pad "29" smd rect
			(at -0.249936 -2.237486 180)
			(size 0.254 0.381)
			(layers "F.Cu" "F.Mask" "F.Paste")
			(net "P12V_AUX")
		)
		(pad "30" smd rect
			(at -0.750062 -2.237486 180)
			(size 0.254 0.381)
			(layers "F.Cu" "F.Mask" "F.Paste")
			(net "P12V_AUX")
		)
		(pad "31" smd rect
			(at -1.249934 -2.237486 180)
			(size 0.254 0.381)
			(layers "F.Cu" "F.Mask" "F.Paste")
			(net "P12V_AUX")
		)
		(pad "32" smd rect
			(at -1.75006 -2.250186 180)
			(size 0.254 0.3556)
			(layers "F.Cu" "F.Mask" "F.Paste")
			(net "P12V_AUX")
		)
		(pad "33" smd rect
			(at 0 0 180)
			(size 3.4036 3.4036)
			(layers "F.Cu" "F.Mask" "F.Paste")
			(net "P12V_PSU")
		)
		(zone
			(layer "F.Cu")
			(hatch none 0.5)
			(connect_pads
				(clearance 0)
			)
			(min_thickness 0.25)
			(keepout
				(tracks not_allowed)
				(vias allowed)
				(pads allowed)
				(copperpour not_allowed)
				(footprints allowed)
			)
			(placement
				(enabled no)
				(sheetname "")
			)
			(fill
				(thermal_gap 0.5)
				(thermal_bridge_width 0.5)
				(island_removal_mode 0)
			)
			(polygon
				(pts
					(xy 212.861652 -401.275042) (xy 212.861652 -400.815048) (xy 212.74786 -400.701256) (xy 212.287866 -400.701256)
					(xy 212.287866 -400.726656) (xy 209.392266 -400.726656) (xy 209.392266 -400.701256) (xy 208.81848 -400.701256)
					(xy 208.81848 -401.275042) (xy 208.84388 -401.275042) (xy 208.84388 -404.170642) (xy 208.81848 -404.170642)
					(xy 208.81848 -404.475442) (xy 209.087466 -404.475442) (xy 209.087466 -400.970242) (xy 212.592666 -400.970242)
					(xy 212.592666 -403.230842) (xy 212.836252 -403.230842) (xy 212.836252 -401.275042)
				)
			)
		)
	)
)
